(kicad_pcb
	(version 20260206)
	(generator "pcbnew")
	(generator_version "10.0")
	(general
		(thickness 1.6)
		(legacy_teardrops no)
	)
	(paper "A4")
	(title_block
		(title "panther-plus-userver — 13130-1b_20150205.brd")
		(comment 1 "Honey Badger (Wiwynn) / footprints 856-863 of 1509")
	)
	(layers
		(0 "F.Cu" signal "TOP")
		(4 "In1.Cu" signal "L2")
		(6 "In2.Cu" signal "L3")
		(8 "In3.Cu" signal "L4")
		(10 "In4.Cu" signal "L5")
		(12 "In5.Cu" signal "L6")
		(14 "In6.Cu" signal "L7")
		(16 "In7.Cu" signal "L8")
		(18 "In8.Cu" signal "L9")
		(20 "In9.Cu" signal "L10")
		(22 "In10.Cu" signal "L11")
		(2 "B.Cu" signal "BOTTOM")
		(9 "F.Adhes" user "F.Adhesive")
		(11 "B.Adhes" user "B.Adhesive")
		(13 "F.Paste" user "Package Geometry/Pastemask Top")
		(15 "B.Paste" user "Package Geometry/Pastemask Bottom")
		(5 "F.SilkS" user "Ref Des/Silkscreen Top")
		(7 "B.SilkS" user "Ref Des/Silkscreen Bottom")
		(1 "F.Mask" user "Board Geometry/Soldermask Top")
		(3 "B.Mask" user "Board Geometry/Soldermask Bottom")
		(17 "Dwgs.User" user "User.Drawings")
		(19 "Cmts.User" user "User.Comments")
		(21 "Eco1.User" user "User.Eco1")
		(23 "Eco2.User" user "User.Eco2")
		(25 "Edge.Cuts" user "Board Geometry/Outline")
		(27 "Margin" user)
		(31 "F.CrtYd" user "Package Geometry/Place Bound Top")
		(29 "B.CrtYd" user "Package Geometry/Place Bound Bottom")
		(35 "F.Fab" user "Ref Des/Assembly Top")
		(33 "B.Fab" user "Ref Des/Assembly Bottom")
	)
	(footprint ""
		(layer "B.Cu")
		(at 44.196 -42.291)
		(property "Reference" "C43"
			(at 0 0 0)
			(layer "B.SilkS")
			(hide yes)
			(effects
				(font
					(size 1.27 1.27)
				)
				(justify mirror)
			)
		)
		(property "Value" "SC10U6D3V3MX-GP"
			(at 0 -2.8194 0)
			(unlocked yes)
			(layer "B.Fab")
			(hide yes)
			(effects
				(font
					(size 1.016 1.016)
					(thickness 0.1524)
				)
				(justify mirror)
			)
		)
		(property "Device Type" "C603H38"
			(at 0 -4.3434 0)
			(unlocked yes)
			(layer "B.Fab")
			(hide yes)
			(effects
				(font
					(size 1.016 1.016)
					(thickness 0.1524)
				)
				(justify mirror)
			)
		)
		(duplicate_pad_numbers_are_jumpers no)
		(fp_line
			(start 0.4064 0)
			(end -0.4064 0)
			(stroke
				(width 0.2286)
				(type default)
			)
			(layer "B.SilkS")
		)
		(fp_rect
			(start 0.635 1.1811)
			(end -0.635 -1.1811)
			(stroke
				(width 0)
				(type default)
			)
			(fill no)
			(layer "B.CrtYd")
		)
		(fp_rect
			(start 0.635 1.1811)
			(end -0.635 -1.1811)
			(stroke
				(width 0)
				(type default)
			)
			(fill no)
			(layer "B.Fab")
		)
		(pad "1" smd custom
			(at 0 -0.6604 180)
			(size 0.19685 0.19685)
			(layers "B.Cu" "B.Mask" "B.Paste")
			(net "P1V5_CLK_VDDDIF")
			(options
				(clearance outline)
				(anchor circle)
			)
			(primitives
				(gr_poly
					(pts
						(arc
							(start 0.508 0.2921)
							(mid 0.478242 0.363942)
							(end 0.4064 0.3937)
						)
						(arc
							(start -0.4064 0.3937)
							(mid -0.478242 0.363942)
							(end -0.508 0.2921)
						)
						(arc
							(start -0.508 -0.2921)
							(mid -0.478242 -0.363942)
							(end -0.4064 -0.3937)
						)
						(arc
							(start 0.4064 -0.3937)
							(mid 0.478242 -0.363942)
							(end 0.508 -0.2921)
						)
					)
					(width 0)
					(fill yes)
				)
			)
		)
		(pad "2" smd custom
			(at 0 0.6604 180)
			(size 0.19685 0.19685)
			(layers "B.Cu" "B.Mask" "B.Paste")
			(net "GND")
			(options
				(clearance outline)
				(anchor circle)
			)
			(primitives
				(gr_poly
					(pts
						(arc
							(start 0.508 0.2921)
							(mid 0.478242 0.363942)
							(end 0.4064 0.3937)
						)
						(arc
							(start -0.4064 0.3937)
							(mid -0.478242 0.363942)
							(end -0.508 0.2921)
						)
						(arc
							(start -0.508 -0.2921)
							(mid -0.478242 -0.363942)
							(end -0.4064 -0.3937)
						)
						(arc
							(start 0.4064 -0.3937)
							(mid 0.478242 -0.363942)
							(end 0.508 -0.2921)
						)
					)
					(width 0)
					(fill yes)
				)
			)
		)
	)
	(footprint ""
		(layer "B.Cu")
		(at 49.657 -29.2608 90)
		(property "Reference" "R361"
			(at 0 0 90)
			(layer "B.SilkS")
			(hide yes)
			(effects
				(font
					(size 1.27 1.27)
				)
				(justify mirror)
			)
		)
		(property "Value" "2D2R3J-2-GP"
			(at 0.0254 -2.5146 90)
			(unlocked yes)
			(layer "B.Fab")
			(hide yes)
			(effects
				(font
					(size 1.016 1.016)
					(thickness 0.1524)
				)
				(justify mirror)
			)
		)
		(property "Device Type" "R603H22"
			(at 0.0254 -4.0386 90)
			(unlocked yes)
			(layer "B.Fab")
			(hide yes)
			(effects
				(font
					(size 1.016 1.016)
					(thickness 0.1524)
				)
				(justify mirror)
			)
		)
		(duplicate_pad_numbers_are_jumpers no)
		(fp_line
			(start 0.2032 0)
			(end 0.4191 0)
			(stroke
				(width 0.2032)
				(type default)
			)
			(layer "B.SilkS")
		)
		(fp_line
			(start -0.4318 0)
			(end -0.2032 0)
			(stroke
				(width 0.2032)
				(type default)
			)
			(layer "B.SilkS")
		)
		(fp_rect
			(start 0.635 1.1811)
			(end -0.635 -1.1811)
			(stroke
				(width 0)
				(type default)
			)
			(fill no)
			(layer "B.CrtYd")
		)
		(fp_rect
			(start 0.635 1.1811)
			(end -0.635 -1.1811)
			(stroke
				(width 0)
				(type default)
			)
			(fill no)
			(layer "B.Fab")
		)
		(pad "1" smd custom
			(at 0 -0.6604 270)
			(size 0.19685 0.19685)
			(layers "B.Cu" "B.Mask" "B.Paste")
			(net "P3V3_VDDA_CLKBUFF_R")
			(options
				(clearance outline)
				(anchor circle)
			)
			(primitives
				(gr_poly
					(pts
						(arc
							(start 0.508 0.2921)
							(mid 0.478242 0.363942)
							(end 0.4064 0.3937)
						)
						(arc
							(start -0.4064 0.3937)
							(mid -0.478242 0.363942)
							(end -0.508 0.2921)
						)
						(arc
							(start -0.508 -0.2921)
							(mid -0.478242 -0.363942)
							(end -0.4064 -0.3937)
						)
						(arc
							(start 0.4064 -0.3937)
							(mid 0.478242 -0.363942)
							(end 0.508 -0.2921)
						)
					)
					(width 0)
					(fill yes)
				)
			)
		)
		(pad "2" smd custom
			(at 0 0.6604 270)
			(size 0.19685 0.19685)
			(layers "B.Cu" "B.Mask" "B.Paste")
			(net "P3V3_VDDA_CLKBUFF")
			(options
				(clearance outline)
				(anchor circle)
			)
			(primitives
				(gr_poly
					(pts
						(arc
							(start 0.508 0.2921)
							(mid 0.478242 0.363942)
							(end 0.4064 0.3937)
						)
						(arc
							(start -0.4064 0.3937)
							(mid -0.478242 0.363942)
							(end -0.508 0.2921)
						)
						(arc
							(start -0.508 -0.2921)
							(mid -0.478242 -0.363942)
							(end -0.4064 -0.3937)
						)
						(arc
							(start 0.4064 -0.3937)
							(mid 0.478242 -0.363942)
							(end 0.508 -0.2921)
						)
					)
					(width 0)
					(fill yes)
				)
			)
		)
	)
	(footprint ""
		(layer "B.Cu")
		(at 68.834 -13.589)
		(property "Reference" "C280"
			(at 0 0 0)
			(layer "B.SilkS")
			(hide yes)
			(effects
				(font
					(size 1.27 1.27)
				)
				(justify mirror)
			)
		)
		(property "Value" "SCD1U16V2KX-3GP"
			(at -1.1811 -2.7051 0)
			(unlocked yes)
			(layer "B.Fab")
			(hide yes)
			(effects
				(font
					(size 1.016 1.016)
					(thickness 0.1524)
				)
				(justify mirror)
			)
		)
		(property "Device Type" "C402H22"
			(at -1.1811 -4.2291 0)
			(unlocked yes)
			(layer "B.Fab")
			(hide yes)
			(effects
				(font
					(size 1.016 1.016)
					(thickness 0.1524)
				)
				(justify mirror)
			)
		)
		(duplicate_pad_numbers_are_jumpers no)
		(fp_rect
			(start 0.381 0.7366)
			(end -0.381 -0.7366)
			(stroke
				(width 0)
				(type default)
			)
			(fill no)
			(layer "B.CrtYd")
		)
		(fp_rect
			(start 0.381 0.7366)
			(end -0.381 -0.7366)
			(stroke
				(width 0)
				(type default)
			)
			(fill no)
			(layer "B.Fab")
		)
		(pad "1" smd custom
			(at 0 -0.4572 180)
			(size 0.1143 0.1143)
			(layers "B.Cu" "B.Mask" "B.Paste")
			(net "P2E_CPU_SAS_C_TX_DP3")
			(options
				(clearance outline)
				(anchor circle)
			)
			(primitives
				(gr_poly
					(pts
						(arc
							(start -0.254 0.1778)
							(mid -0.239121 0.213721)
							(end -0.2032 0.2286)
						)
						(arc
							(start 0.2032 0.2286)
							(mid 0.239121 0.213721)
							(end 0.254 0.1778)
						)
						(arc
							(start 0.254 -0.1778)
							(mid 0.239121 -0.213721)
							(end 0.2032 -0.2286)
						)
						(arc
							(start -0.2032 -0.2286)
							(mid -0.239121 -0.213721)
							(end -0.254 -0.1778)
						)
					)
					(width 0)
					(fill yes)
				)
			)
		)
		(pad "2" smd custom
			(at 0 0.4572 180)
			(size 0.1143 0.1143)
			(layers "B.Cu" "B.Mask" "B.Paste")
			(net "P2E_CPU_SAS_TX_DP3")
			(options
				(clearance outline)
				(anchor circle)
			)
			(primitives
				(gr_poly
					(pts
						(arc
							(start -0.254 0.1778)
							(mid -0.239121 0.213721)
							(end -0.2032 0.2286)
						)
						(arc
							(start 0.2032 0.2286)
							(mid 0.239121 0.213721)
							(end 0.254 0.1778)
						)
						(arc
							(start 0.254 -0.1778)
							(mid 0.239121 -0.213721)
							(end 0.2032 -0.2286)
						)
						(arc
							(start -0.2032 -0.2286)
							(mid -0.239121 -0.213721)
							(end -0.254 -0.1778)
						)
					)
					(width 0)
					(fill yes)
				)
			)
		)
	)
	(footprint ""
		(layer "B.Cu")
		(at 51.943 -17.018)
		(property "Reference" "C209"
			(at 0 0 0)
			(layer "B.SilkS")
			(hide yes)
			(effects
				(font
					(size 1.27 1.27)
				)
				(justify mirror)
			)
		)
		(property "Value" "SCD1U10V2KX-5GP"
			(at -1.1811 -2.7051 0)
			(unlocked yes)
			(layer "B.Fab")
			(hide yes)
			(effects
				(font
					(size 1.016 1.016)
					(thickness 0.1524)
				)
				(justify mirror)
			)
		)
		(property "Device Type" "C402H22"
			(at -1.1811 -4.2291 0)
			(unlocked yes)
			(layer "B.Fab")
			(hide yes)
			(effects
				(font
					(size 1.016 1.016)
					(thickness 0.1524)
				)
				(justify mirror)
			)
		)
		(duplicate_pad_numbers_are_jumpers no)
		(fp_rect
			(start 0.381 0.7366)
			(end -0.381 -0.7366)
			(stroke
				(width 0)
				(type default)
			)
			(fill no)
			(layer "B.CrtYd")
		)
		(fp_rect
			(start 0.381 0.7366)
			(end -0.381 -0.7366)
			(stroke
				(width 0)
				(type default)
			)
			(fill no)
			(layer "B.Fab")
		)
		(pad "1" smd custom
			(at 0 -0.4572 180)
			(size 0.1143 0.1143)
			(layers "B.Cu" "B.Mask" "B.Paste")
			(net "P3V3_VDDA_CLKBUFF")
			(options
				(clearance outline)
				(anchor circle)
			)
			(primitives
				(gr_poly
					(pts
						(arc
							(start -0.254 0.1778)
							(mid -0.239121 0.213721)
							(end -0.2032 0.2286)
						)
						(arc
							(start 0.2032 0.2286)
							(mid 0.239121 0.213721)
							(end 0.254 0.1778)
						)
						(arc
							(start 0.254 -0.1778)
							(mid 0.239121 -0.213721)
							(end 0.2032 -0.2286)
						)
						(arc
							(start -0.2032 -0.2286)
							(mid -0.239121 -0.213721)
							(end -0.254 -0.1778)
						)
					)
					(width 0)
					(fill yes)
				)
			)
		)
		(pad "2" smd custom
			(at 0 0.4572 180)
			(size 0.1143 0.1143)
			(layers "B.Cu" "B.Mask" "B.Paste")
			(net "GND")
			(options
				(clearance outline)
				(anchor circle)
			)
			(primitives
				(gr_poly
					(pts
						(arc
							(start -0.254 0.1778)
							(mid -0.239121 0.213721)
							(end -0.2032 0.2286)
						)
						(arc
							(start 0.2032 0.2286)
							(mid 0.239121 0.213721)
							(end 0.254 0.1778)
						)
						(arc
							(start 0.254 -0.1778)
							(mid 0.239121 -0.213721)
							(end 0.2032 -0.2286)
						)
						(arc
							(start -0.2032 -0.2286)
							(mid -0.239121 -0.213721)
							(end -0.254 -0.1778)
						)
					)
					(width 0)
					(fill yes)
				)
			)
		)
	)
	(footprint ""
		(layer "B.Cu")
		(at 91.948 -62.738 -90)
		(property "Reference" "PC7"
			(at 0 0 90)
			(layer "B.SilkS")
			(hide yes)
			(effects
				(font
					(size 1.27 1.27)
				)
				(justify mirror)
			)
		)
		(property "Value" "SC47U6D3V5MX-1-GP"
			(at 0 -4.9022 270)
			(unlocked yes)
			(layer "B.Fab")
			(hide yes)
			(effects
				(font
					(size 1.016 1.016)
					(thickness 0.1524)
				)
				(justify mirror)
			)
		)
		(property "Device Type" "C805H54"
			(at 0 -6.8072 270)
			(unlocked yes)
			(layer "B.Fab")
			(hide yes)
			(effects
				(font
					(size 1.016 1.016)
					(thickness 0.1524)
				)
				(justify mirror)
			)
		)
		(duplicate_pad_numbers_are_jumpers no)
		(fp_line
			(start -0.6096 0)
			(end 0.6096 0)
			(stroke
				(width 0.3048)
				(type default)
			)
			(layer "B.SilkS")
		)
		(fp_poly
			(pts
				(xy 0.9017 1.4351) (xy -0.9017 1.4351) (xy -0.9017 -1.4351) (xy 0.9017 -1.4351)
			)
			(stroke
				(width 0)
				(type default)
			)
			(fill no)
			(layer "B.CrtYd")
		)
		(fp_poly
			(pts
				(xy -0.9017 1.4351) (xy -0.9017 -1.4351) (xy 0.9017 -1.4351) (xy 0.9017 1.4351)
			)
			(stroke
				(width 0)
				(type default)
			)
			(fill no)
			(layer "B.Fab")
		)
		(pad "1" smd rect
			(at 0 -0.8382 90)
			(size 1.5494 0.9398)
			(layers "B.Cu" "B.Mask" "B.Paste")
			(net "P1V1")
		)
		(pad "2" smd rect
			(at 0 0.8382 90)
			(size 1.5494 0.9398)
			(layers "B.Cu" "B.Mask" "B.Paste")
			(net "GND")
		)
	)
	(footprint ""
		(layer "B.Cu")
		(at 20.447 -27.94 90)
		(property "Reference" "PR86"
			(at 0 0 90)
			(layer "B.SilkS")
			(hide yes)
			(effects
				(font
					(size 1.27 1.27)
				)
				(justify mirror)
			)
		)
		(property "Value" "2K21R2F-GP"
			(at -1.7907 -1.1176 90)
			(unlocked yes)
			(layer "B.Fab")
			(hide yes)
			(effects
				(font
					(size 1.016 1.016)
					(thickness 0.1524)
				)
				(justify mirror)
			)
		)
		(property "Device Type" "R402H16"
			(at -1.7907 -2.6416 90)
			(unlocked yes)
			(layer "B.Fab")
			(hide yes)
			(effects
				(font
					(size 1.016 1.016)
					(thickness 0.1524)
				)
				(justify mirror)
			)
		)
		(duplicate_pad_numbers_are_jumpers no)
		(fp_rect
			(start 0.381 0.8382)
			(end -0.381 -0.8382)
			(stroke
				(width 0)
				(type default)
			)
			(fill no)
			(layer "B.CrtYd")
		)
		(fp_rect
			(start 0.381 0.8382)
			(end -0.381 -0.8382)
			(stroke
				(width 0)
				(type default)
			)
			(fill no)
			(layer "B.Fab")
		)
		(pad "1" smd custom
			(at 0 -0.4318 270)
			(size 0.127 0.127)
			(layers "B.Cu" "B.Mask" "B.Paste")
			(net "P1V0_LX")
			(options
				(clearance outline)
				(anchor circle)
			)
			(primitives
				(gr_poly
					(pts
						(arc
							(start -0.2032 0.2794)
							(mid -0.239121 0.264521)
							(end -0.254 0.2286)
						)
						(arc
							(start -0.254 -0.2286)
							(mid -0.239121 -0.264521)
							(end -0.2032 -0.2794)
						)
						(arc
							(start 0.2032 -0.2794)
							(mid 0.239121 -0.264521)
							(end 0.254 -0.2286)
						)
						(arc
							(start 0.254 0.2286)
							(mid 0.239121 0.264521)
							(end 0.2032 0.2794)
						)
					)
					(width 0)
					(fill yes)
				)
			)
		)
		(pad "2" smd custom
			(at 0 0.4318 270)
			(size 0.127 0.127)
			(layers "B.Cu" "B.Mask" "B.Paste")
			(net "P1V0_SW_R")
			(options
				(clearance outline)
				(anchor circle)
			)
			(primitives
				(gr_poly
					(pts
						(arc
							(start -0.2032 0.2794)
							(mid -0.239121 0.264521)
							(end -0.254 0.2286)
						)
						(arc
							(start -0.254 -0.2286)
							(mid -0.239121 -0.264521)
							(end -0.2032 -0.2794)
						)
						(arc
							(start 0.2032 -0.2794)
							(mid 0.239121 -0.264521)
							(end 0.254 -0.2286)
						)
						(arc
							(start 0.254 0.2286)
							(mid 0.239121 0.264521)
							(end 0.2032 0.2794)
						)
					)
					(width 0)
					(fill yes)
				)
			)
		)
	)
	(footprint ""
		(layer "B.Cu")
		(at 187.5282 -31.7246 180)
		(property "Reference" "PR144"
			(at 0 0 0)
			(layer "B.SilkS")
			(hide yes)
			(effects
				(font
					(size 1.27 1.27)
				)
				(justify mirror)
			)
		)
		(property "Value" "20KR2F-L-GP"
			(at -1.7907 -1.1176 180)
			(unlocked yes)
			(layer "B.Fab")
			(hide yes)
			(effects
				(font
					(size 1.016 1.016)
					(thickness 0.1524)
				)
				(justify mirror)
			)
		)
		(property "Device Type" "R402H16"
			(at -1.7907 -2.6416 180)
			(unlocked yes)
			(layer "B.Fab")
			(hide yes)
			(effects
				(font
					(size 1.016 1.016)
					(thickness 0.1524)
				)
				(justify mirror)
			)
		)
		(duplicate_pad_numbers_are_jumpers no)
		(fp_rect
			(start 0.381 0.8382)
			(end -0.381 -0.8382)
			(stroke
				(width 0)
				(type default)
			)
			(fill no)
			(layer "B.CrtYd")
		)
		(fp_rect
			(start 0.381 0.8382)
			(end -0.381 -0.8382)
			(stroke
				(width 0)
				(type default)
			)
			(fill no)
			(layer "B.Fab")
		)
		(pad "1" smd custom
			(at 0 -0.4318)
			(size 0.127 0.127)
			(layers "B.Cu" "B.Mask" "B.Paste")
			(net "VR_PVDDR_A_NTC_R")
			(options
				(clearance outline)
				(anchor circle)
			)
			(primitives
				(gr_poly
					(pts
						(arc
							(start -0.2032 0.2794)
							(mid -0.239121 0.264521)
							(end -0.254 0.2286)
						)
						(arc
							(start -0.254 -0.2286)
							(mid -0.239121 -0.264521)
							(end -0.2032 -0.2794)
						)
						(arc
							(start 0.2032 -0.2794)
							(mid 0.239121 -0.264521)
							(end 0.254 -0.2286)
						)
						(arc
							(start 0.254 0.2286)
							(mid 0.239121 0.264521)
							(end 0.2032 0.2794)
						)
					)
					(width 0)
					(fill yes)
				)
			)
		)
		(pad "2" smd custom
			(at 0 0.4318)
			(size 0.127 0.127)
			(layers "B.Cu" "B.Mask" "B.Paste")
			(net "GND")
			(options
				(clearance outline)
				(anchor circle)
			)
			(primitives
				(gr_poly
					(pts
						(arc
							(start -0.2032 0.2794)
							(mid -0.239121 0.264521)
							(end -0.254 0.2286)
						)
						(arc
							(start -0.254 -0.2286)
							(mid -0.239121 -0.264521)
							(end -0.2032 -0.2794)
						)
						(arc
							(start 0.2032 -0.2794)
							(mid 0.239121 -0.264521)
							(end 0.254 -0.2286)
						)
						(arc
							(start 0.254 0.2286)
							(mid 0.239121 0.264521)
							(end 0.2032 0.2794)
						)
					)
					(width 0)
					(fill yes)
				)
			)
		)
	)
	(footprint ""
		(layer "B.Cu")
		(at 96.4438 -39.9923 -90)
		(property "Reference" "TP26"
			(at 0 0 90)
			(layer "B.SilkS")
			(hide yes)
			(effects
				(font
					(size 1.27 1.27)
				)
				(justify mirror)
			)
		)
		(property "Value" "TPAD24"
			(at 0 -2.9972 270)
			(unlocked yes)
			(layer "B.Fab")
			(hide yes)
			(effects
				(font
					(size 1.016 1.016)
					(thickness 0.1524)
				)
				(justify mirror)
			)
		)
		(property "Device Type" "TPAD24"
			(at 0 -4.5212 270)
			(unlocked yes)
			(layer "B.Fab")
			(hide yes)
			(effects
				(font
					(size 1.016 1.016)
					(thickness 0.1524)
				)
				(justify mirror)
			)
		)
		(duplicate_pad_numbers_are_jumpers no)
		(fp_poly
			(pts
				(arc
					(start 0 -0.3048)
					(mid 0 0.3048)
					(end 0 -0.3048)
				)
			)
			(stroke
				(width 0)
				(type default)
			)
			(fill no)
			(layer "B.CrtYd")
		)
		(fp_poly
			(pts
				(arc
					(start 0 -0.6096)
					(mid 0 0.6096)
					(end 0 -0.6096)
				)
			)
			(stroke
				(width 0)
				(type default)
			)
			(fill no)
			(layer "B.Fab")
		)
		(pad "1" smd circle
			(at 0 0 90)
			(size 0.6096 0.6096)
			(layers "B.Cu" "B.Mask" "B.Paste")
			(net "VCCCORE7VIDSI0GT_1P03")
		)
	)
)
